# T6G (Grand Teton) — schematic netlist excerpt (pin names and nets, part order shuffled) for the footprints in the layout excerpt that follows; sources: Cadence DE-HDL packaged netlist, KiCad conversion of 04192023_DAF0TMB3IC0_F0TG_MB_C_brd_V02_OCP.brd

PR6553  Q_RES  8.87K 1% EMPTY  pkg 0402LF  page 363 : A = P0V9_RETIMER_CPU0_LSET1 ; B = GND
R4514  Q_RES  4.7K 1% EMPTY  pkg 0402LF  page 233 : A = CLK_GEN2_GPU_FPGA_OE_R2_N ; B = GND

(kicad_pcb
	(version 20260206)
	(generator "pcbnew")
	(generator_version "10.0")
	(general
		(thickness 1.6)
		(legacy_teardrops no)
	)
	(paper "A4")
	(title_block
		(title "04192023_DAF0TMB3IC0_F0TG_MB_C_brd_V02_OCP.brd")
		(comment 1 "Grand Teton / footprints 2181-2182 of 8354")
	)
	(layers
		(0 "F.Cu" signal "TOP")
		(4 "In1.Cu" signal "GND")
		(6 "In2.Cu" signal "IN1")
		(8 "In3.Cu" signal "GND1")
		(10 "In4.Cu" signal "IN2")
		(12 "In5.Cu" signal "GND2")
		(14 "In6.Cu" signal "IN3")
		(16 "In7.Cu" signal "GND3")
		(18 "In8.Cu" signal "VCC")
		(20 "In9.Cu" signal "VCC1")
		(22 "In10.Cu" signal "GND4")
		(24 "In11.Cu" signal "IN4")
		(26 "In12.Cu" signal "GND5")
		(28 "In13.Cu" signal "IN5")
		(30 "In14.Cu" signal "GND6")
		(32 "In15.Cu" signal "IN6")
		(34 "In16.Cu" signal "GND7")
		(2 "B.Cu" signal "BOTTOM")
		(9 "F.Adhes" user "F.Adhesive")
		(11 "B.Adhes" user "B.Adhesive")
		(13 "F.Paste" user "Package Geometry/Pastemask Top")
		(15 "B.Paste" user "Package Geometry/Pastemask Bottom")
		(5 "F.SilkS" user "Ref Des/Silkscreen Top")
		(7 "B.SilkS" user "Ref Des/Silkscreen Bottom")
		(1 "F.Mask" user "Board Geometry/Soldermask Top")
		(3 "B.Mask" user "Board Geometry/Soldermask Bottom")
		(17 "Dwgs.User" user "User.Drawings")
		(19 "Cmts.User" user "User.Comments")
		(21 "Eco1.User" user "User.Eco1")
		(23 "Eco2.User" user "User.Eco2")
		(25 "Edge.Cuts" user "Board Geometry/Outline")
		(27 "Margin" user)
		(31 "F.CrtYd" user "Package Geometry/Place Bound Top")
		(29 "B.CrtYd" user "Package Geometry/Place Bound Bottom")
		(35 "F.Fab" user "Ref Des/Assembly Top")
		(33 "B.Fab" user "Ref Des/Assembly Bottom")
	)
	(footprint ""
		(layer "F.Cu")
		(at 444.621666 -402.81987)
		(property "Reference" "PR6553"
			(at 0 0 0)
			(layer "F.SilkS")
			(hide yes)
			(effects
				(font
					(size 1.27 1.27)
				)
			)
		)
		(property "Value" ""
			(at 0 0 0)
			(layer "F.Fab")
			(effects
				(font
					(size 1.27 1.27)
				)
			)
		)
		(duplicate_pad_numbers_are_jumpers no)
		(fp_line
			(start -0.7874 -0.4064)
			(end 0.7874 -0.4064)
			(stroke
				(width 0.1524)
				(type default)
			)
			(layer "F.SilkS")
		)
		(fp_line
			(start -0.7874 0.4064)
			(end -0.7874 -0.4064)
			(stroke
				(width 0.1524)
				(type default)
			)
			(layer "F.SilkS")
		)
		(fp_line
			(start 0.7874 -0.4064)
			(end 0.7874 0.4064)
			(stroke
				(width 0.1524)
				(type default)
			)
			(layer "F.SilkS")
		)
		(fp_line
			(start 0.7874 0.4064)
			(end -0.7874 0.4064)
			(stroke
				(width 0.1524)
				(type default)
			)
			(layer "F.SilkS")
		)
		(fp_line
			(start -0.67945 -0.305054)
			(end -0.12065 -0.305054)
			(stroke
				(width 0.1)
				(type default)
			)
			(layer "F.Fab")
		)
		(fp_line
			(start -0.67945 0.3048)
			(end -0.67945 -0.305054)
			(stroke
				(width 0.1)
				(type default)
			)
			(layer "F.Fab")
		)
		(fp_line
			(start -0.12065 -0.305054)
			(end -0.12065 -0.2794)
			(stroke
				(width 0.1)
				(type default)
			)
			(layer "F.Fab")
		)
		(fp_line
			(start -0.12065 -0.2794)
			(end 0.12065 -0.2794)
			(stroke
				(width 0.1)
				(type default)
			)
			(layer "F.Fab")
		)
		(fp_line
			(start -0.12065 0.2794)
			(end -0.12065 0.3048)
			(stroke
				(width 0.1)
				(type default)
			)
			(layer "F.Fab")
		)
		(fp_line
			(start -0.12065 0.3048)
			(end -0.67945 0.3048)
			(stroke
				(width 0.1)
				(type default)
			)
			(layer "F.Fab")
		)
		(fp_line
			(start 0.120396 0.2794)
			(end -0.12065 0.2794)
			(stroke
				(width 0.1)
				(type default)
			)
			(layer "F.Fab")
		)
		(fp_line
			(start 0.120396 0.3048)
			(end 0.120396 0.2794)
			(stroke
				(width 0.1)
				(type default)
			)
			(layer "F.Fab")
		)
		(fp_line
			(start 0.12065 -0.3048)
			(end 0.67945 -0.3048)
			(stroke
				(width 0.1)
				(type default)
			)
			(layer "F.Fab")
		)
		(fp_line
			(start 0.12065 -0.2794)
			(end 0.12065 -0.3048)
			(stroke
				(width 0.1)
				(type default)
			)
			(layer "F.Fab")
		)
		(fp_line
			(start 0.67945 -0.3048)
			(end 0.67945 0.3048)
			(stroke
				(width 0.1)
				(type default)
			)
			(layer "F.Fab")
		)
		(fp_line
			(start 0.67945 0.3048)
			(end 0.120396 0.3048)
			(stroke
				(width 0.1)
				(type default)
			)
			(layer "F.Fab")
		)
		(pad "1" smd circle
			(at -0.40005 0)
			(size 0 0)
			(layers "F.Cu" "F.Mask" "F.Paste")
			(net "P0V9_RETIMER_CPU0_LSET1")
		)
		(pad "2" smd circle
			(at 0.40005 0)
			(size 0 0)
			(layers "F.Cu" "F.Mask" "F.Paste")
			(net "GND")
		)
	)
	(footprint ""
		(layer "F.Cu")
		(at 36.319968 -133.857238)
		(property "Reference" "R4514"
			(at 0 0 0)
			(layer "F.SilkS")
			(hide yes)
			(effects
				(font
					(size 1.27 1.27)
				)
			)
		)
		(property "Value" ""
			(at 0 0 0)
			(layer "F.Fab")
			(effects
				(font
					(size 1.27 1.27)
				)
			)
		)
		(duplicate_pad_numbers_are_jumpers no)
		(fp_line
			(start -0.7874 -0.4064)
			(end 0.7874 -0.4064)
			(stroke
				(width 0.1524)
				(type default)
			)
			(layer "F.SilkS")
		)
		(fp_line
			(start -0.7874 0.4064)
			(end -0.7874 -0.4064)
			(stroke
				(width 0.1524)
				(type default)
			)
			(layer "F.SilkS")
		)
		(fp_line
			(start 0.7874 -0.4064)
			(end 0.7874 0.4064)
			(stroke
				(width 0.1524)
				(type default)
			)
			(layer "F.SilkS")
		)
		(fp_line
			(start 0.7874 0.4064)
			(end -0.7874 0.4064)
			(stroke
				(width 0.1524)
				(type default)
			)
			(layer "F.SilkS")
		)
		(fp_line
			(start -0.67945 -0.305054)
			(end -0.12065 -0.305054)
			(stroke
				(width 0.1)
				(type default)
			)
			(layer "F.Fab")
		)
		(fp_line
			(start -0.67945 0.3048)
			(end -0.67945 -0.305054)
			(stroke
				(width 0.1)
				(type default)
			)
			(layer "F.Fab")
		)
		(fp_line
			(start -0.12065 -0.305054)
			(end -0.12065 -0.2794)
			(stroke
				(width 0.1)
				(type default)
			)
			(layer "F.Fab")
		)
		(fp_line
			(start -0.12065 -0.2794)
			(end 0.12065 -0.2794)
			(stroke
				(width 0.1)
				(type default)
			)
			(layer "F.Fab")
		)
		(fp_line
			(start -0.12065 0.2794)
			(end -0.12065 0.3048)
			(stroke
				(width 0.1)
				(type default)
			)
			(layer "F.Fab")
		)
		(fp_line
			(start -0.12065 0.3048)
			(end -0.67945 0.3048)
			(stroke
				(width 0.1)
				(type default)
			)
			(layer "F.Fab")
		)
		(fp_line
			(start 0.120396 0.2794)
			(end -0.12065 0.2794)
			(stroke
				(width 0.1)
				(type default)
			)
			(layer "F.Fab")
		)
		(fp_line
			(start 0.120396 0.3048)
			(end 0.120396 0.2794)
			(stroke
				(width 0.1)
				(type default)
			)
			(layer "F.Fab")
		)
		(fp_line
			(start 0.12065 -0.3048)
			(end 0.67945 -0.3048)
			(stroke
				(width 0.1)
				(type default)
			)
			(layer "F.Fab")
		)
		(fp_line
			(start 0.12065 -0.2794)
			(end 0.12065 -0.3048)
			(stroke
				(width 0.1)
				(type default)
			)
			(layer "F.Fab")
		)
		(fp_line
			(start 0.67945 -0.3048)
			(end 0.67945 0.3048)
			(stroke
				(width 0.1)
				(type default)
			)
			(layer "F.Fab")
		)
		(fp_line
			(start 0.67945 0.3048)
			(end 0.120396 0.3048)
			(stroke
				(width 0.1)
				(type default)
			)
			(layer "F.Fab")
		)
		(pad "1" smd circle
			(at -0.40005 0)
			(size 0 0)
			(layers "F.Cu" "F.Mask" "F.Paste")
			(net "CLK_GEN2_GPU_FPGA_OE_R2_N")
		)
		(pad "2" smd circle
			(at 0.40005 0)
			(size 0 0)
			(layers "F.Cu" "F.Mask" "F.Paste")
			(net "GND")
		)
	)
)
